G04*
G04 #@! TF.GenerationSoftware,Altium Limited,Altium Designer,23.6.0 (18)*
G04*
G04 Layer_Color=8421504*
%FSLAX44Y44*%
%MOMM*%
G71*
G04*
G04 #@! TF.SameCoordinates,59133E90-4310-4D8A-9E2C-91A8D2F69FBB*
G04*
G04*
G04 #@! TF.FilePolarity,Positive*
G04*
G01*
G75*
%ADD14R,0.5153X0.4725*%
%ADD15R,0.5000X0.6000*%
%ADD16R,0.6000X0.5500*%
%ADD17R,0.6153X0.5725*%
%ADD18R,1.7062X1.1546*%
%ADD19R,1.1000X1.1000*%
%ADD20R,0.8000X1.5000*%
%ADD21R,1.5000X0.8000*%
%ADD22R,0.8000X0.8000*%
%ADD23R,0.9000X0.8000*%
%ADD24R,4.9000X1.1000*%
G04:AMPARAMS|DCode=25|XSize=0.4mm|YSize=0.85mm|CornerRadius=0.05mm|HoleSize=0mm|Usage=FLASHONLY|Rotation=180.000|XOffset=0mm|YOffset=0mm|HoleType=Round|Shape=RoundedRectangle|*
%AMROUNDEDRECTD25*
21,1,0.4000,0.7500,0,0,180.0*
21,1,0.3000,0.8500,0,0,180.0*
1,1,0.1000,-0.1500,0.3750*
1,1,0.1000,0.1500,0.3750*
1,1,0.1000,0.1500,-0.3750*
1,1,0.1000,-0.1500,-0.3750*
%
%ADD25ROUNDEDRECTD25*%
G04:AMPARAMS|DCode=26|XSize=0.3mm|YSize=0.8mm|CornerRadius=0.0495mm|HoleSize=0mm|Usage=FLASHONLY|Rotation=0.000|XOffset=0mm|YOffset=0mm|HoleType=Round|Shape=RoundedRectangle|*
%AMROUNDEDRECTD26*
21,1,0.3000,0.7010,0,0,0.0*
21,1,0.2010,0.8000,0,0,0.0*
1,1,0.0990,0.1005,-0.3505*
1,1,0.0990,-0.1005,-0.3505*
1,1,0.0990,-0.1005,0.3505*
1,1,0.0990,0.1005,0.3505*
%
%ADD26ROUNDEDRECTD26*%
%ADD27R,0.5725X0.6153*%
%ADD28R,1.0500X2.2000*%
%ADD29R,1.0000X1.0500*%
%ADD30R,0.3627X0.4541*%
%ADD31R,0.8500X0.6500*%
%ADD32R,0.6000X0.5000*%
%ADD33R,0.5811X0.4725*%
%ADD34R,0.4725X0.5811*%
%ADD35R,0.5500X0.6000*%
%ADD36R,0.3500X1.4500*%
%ADD37R,1.1546X1.7062*%
D14*
X106214Y155000D02*
D03*
X113786D02*
D03*
X67786Y127000D02*
D03*
X60214D02*
D03*
X135786Y145000D02*
D03*
X128214D02*
D03*
X135786Y155000D02*
D03*
X128214D02*
D03*
X84237Y155226D02*
D03*
X91808D02*
D03*
D15*
X77000Y373250D02*
D03*
X87000D02*
D03*
X165000Y97000D02*
D03*
X155000D02*
D03*
X22000Y131000D02*
D03*
X32000D02*
D03*
X59000Y140000D02*
D03*
X69000D02*
D03*
D16*
X83250Y101000D02*
D03*
X74750D02*
D03*
X83250Y112000D02*
D03*
X74750D02*
D03*
D17*
X162593Y364779D02*
D03*
X171164D02*
D03*
X22714Y410000D02*
D03*
X31286D02*
D03*
D18*
X202000Y51242D02*
D03*
Y76758D02*
D03*
D19*
X184000Y194600D02*
D03*
X163000Y194600D02*
D03*
X142000D02*
D03*
X121000D02*
D03*
X100000D02*
D03*
X79000D02*
D03*
X58000D02*
D03*
X37000D02*
D03*
X184000Y215600D02*
D03*
X163000Y215600D02*
D03*
X142000D02*
D03*
X121000D02*
D03*
X100000D02*
D03*
X79000D02*
D03*
X58000D02*
D03*
X37000D02*
D03*
X184000Y236600D02*
D03*
X163000Y236600D02*
D03*
X142000D02*
D03*
X121000D02*
D03*
X100000D02*
D03*
X79000D02*
D03*
X58000D02*
D03*
X37000D02*
D03*
X184000Y257600D02*
D03*
X163000Y257600D02*
D03*
X142000D02*
D03*
X121000D02*
D03*
X100000D02*
D03*
X79000D02*
D03*
X58000D02*
D03*
X37000D02*
D03*
X184000Y278600D02*
D03*
X163000Y278600D02*
D03*
X142000D02*
D03*
X121000D02*
D03*
X100000D02*
D03*
X79000D02*
D03*
X58000D02*
D03*
X37000D02*
D03*
X184000Y299600D02*
D03*
X163000Y299600D02*
D03*
X142000D02*
D03*
X121000D02*
D03*
X100000D02*
D03*
X79000D02*
D03*
X58000D02*
D03*
X37000D02*
D03*
D20*
X182000Y172600D02*
D03*
X171000D02*
D03*
X160000D02*
D03*
X149000D02*
D03*
X138000D02*
D03*
X127000D02*
D03*
X116000D02*
D03*
X105000D02*
D03*
X94000D02*
D03*
X83000D02*
D03*
X72000D02*
D03*
X61000D02*
D03*
X50000D02*
D03*
X39000D02*
D03*
Y321600D02*
D03*
X50000D02*
D03*
X61000D02*
D03*
X72000D02*
D03*
X83000D02*
D03*
X94000D02*
D03*
X105000D02*
D03*
X116000D02*
D03*
X127000D02*
D03*
X138000D02*
D03*
X149000D02*
D03*
X160000D02*
D03*
X171000D02*
D03*
X182000D02*
D03*
D21*
X11000Y181100D02*
D03*
Y192100D02*
D03*
Y203100D02*
D03*
Y214100D02*
D03*
Y225100D02*
D03*
Y236100D02*
D03*
Y247100D02*
D03*
Y258100D02*
D03*
Y269100D02*
D03*
Y280100D02*
D03*
Y291100D02*
D03*
Y302100D02*
D03*
Y313100D02*
D03*
X210000D02*
D03*
Y258100D02*
D03*
Y269100D02*
D03*
Y302100D02*
D03*
Y291100D02*
D03*
Y280100D02*
D03*
Y247100D02*
D03*
Y236100D02*
D03*
Y225100D02*
D03*
Y214100D02*
D03*
Y203100D02*
D03*
Y192100D02*
D03*
Y181100D02*
D03*
D22*
X191500Y97000D02*
D03*
X176500D02*
D03*
X32878Y117328D02*
D03*
X17879D02*
D03*
D23*
X66000Y361500D02*
D03*
Y342500D02*
D03*
X86000Y352000D02*
D03*
D24*
X120000Y348000D02*
D03*
Y376000D02*
D03*
D25*
X44500Y385480D02*
D03*
X51000D02*
D03*
X57500D02*
D03*
Y407980D02*
D03*
X44500D02*
D03*
D26*
X13500Y360000D02*
D03*
X18500D02*
D03*
X23500D02*
D03*
X28500D02*
D03*
X13500Y392000D02*
D03*
X18500D02*
D03*
X23500D02*
D03*
X28500D02*
D03*
D27*
X171000Y353286D02*
D03*
Y344714D02*
D03*
X40000Y345714D02*
D03*
Y354286D02*
D03*
D28*
X156554Y404624D02*
D03*
X186054D02*
D03*
D29*
X171304Y389374D02*
D03*
D30*
X151962Y357973D02*
D03*
Y364059D02*
D03*
D31*
X171295Y375639D02*
D03*
X183795D02*
D03*
D32*
X11000Y339000D02*
D03*
Y349000D02*
D03*
X26000Y339000D02*
D03*
Y349000D02*
D03*
D33*
X66655Y373238D02*
D03*
X59345D02*
D03*
D34*
X54000Y352345D02*
D03*
Y359655D02*
D03*
D35*
X114000Y73750D02*
D03*
Y82250D02*
D03*
X104000Y73750D02*
D03*
Y82250D02*
D03*
X69000Y85250D02*
D03*
Y76750D02*
D03*
X81000Y85250D02*
D03*
Y76750D02*
D03*
D36*
X17500Y12750D02*
D03*
X22500D02*
D03*
X27500D02*
D03*
X32500D02*
D03*
X37500D02*
D03*
X42500D02*
D03*
X47500D02*
D03*
X52500D02*
D03*
X57500D02*
D03*
X62500D02*
D03*
X67500D02*
D03*
X72500D02*
D03*
X77500D02*
D03*
X82500D02*
D03*
X87500D02*
D03*
X92500D02*
D03*
X97500D02*
D03*
X102500D02*
D03*
X107500D02*
D03*
X112500D02*
D03*
X117500D02*
D03*
X122500D02*
D03*
X127500D02*
D03*
X132500D02*
D03*
X137500D02*
D03*
X142500D02*
D03*
X147500D02*
D03*
X152500D02*
D03*
X187500D02*
D03*
X192500D02*
D03*
X197500D02*
D03*
X202500D02*
D03*
X182500D02*
D03*
X177500D02*
D03*
D37*
X12242Y68000D02*
D03*
X37758D02*
D03*
M02*
